(kicad_pcb
	(version 20260206)
	(generator "pcbnew")
	(generator_version "10.0")
	(general
		(thickness 1.6)
		(legacy_teardrops no)
	)
	(paper "A4")
	(title_block
		(title "pdpb — Lightning_PDPB_BRD.brd")
		(comment 1 "Lightning (Wiwynn / Facebook NVMe JBOF) / footprints 291-296 of 1140")
	)
	(layers
		(0 "F.Cu" signal "TOP")
		(4 "In1.Cu" signal "L2GND")
		(6 "In2.Cu" signal "L3")
		(8 "In3.Cu" signal "L4VCC")
		(10 "In4.Cu" signal "L5VCC")
		(12 "In5.Cu" signal "L6")
		(14 "In6.Cu" signal "L7GND")
		(2 "B.Cu" signal "BOTTOM")
		(9 "F.Adhes" user "F.Adhesive")
		(11 "B.Adhes" user "B.Adhesive")
		(13 "F.Paste" user "Package Geometry/Pastemask Top")
		(15 "B.Paste" user "Package Geometry/Pastemask Bottom")
		(5 "F.SilkS" user "Ref Des/Silkscreen Top")
		(7 "B.SilkS" user "Ref Des/Silkscreen Bottom")
		(1 "F.Mask" user "Board Geometry/Soldermask Top")
		(3 "B.Mask" user "Board Geometry/Soldermask Bottom")
		(17 "Dwgs.User" user "User.Drawings")
		(19 "Cmts.User" user "User.Comments")
		(21 "Eco1.User" user "User.Eco1")
		(23 "Eco2.User" user "User.Eco2")
		(25 "Edge.Cuts" user "Board Geometry/Outline")
		(27 "Margin" user)
		(31 "F.CrtYd" user "Package Geometry/Place Bound Top")
		(29 "B.CrtYd" user "Package Geometry/Place Bound Bottom")
		(35 "F.Fab" user "Ref Des/Assembly Top")
		(33 "B.Fab" user "Ref Des/Assembly Bottom")
	)
	(footprint ""
		(layer "F.Cu")
		(at 41.654476 -38.871144 180)
		(property "Reference" "R9946"
			(at 0 0 180)
			(layer "F.SilkS")
			(hide yes)
			(effects
				(font
					(size 1.27 1.27)
				)
			)
		)
		(property "Value" "4K7R2J-2-GP"
			(at 0.064008 -3.993896 180)
			(unlocked yes)
			(layer "F.Fab")
			(hide yes)
			(effects
				(font
					(size 1.016 1.016)
					(thickness 0.1524)
				)
			)
		)
		(property "Device Type" "R402H16"
			(at 0.064008 -5.517896 180)
			(unlocked yes)
			(layer "F.Fab")
			(hide yes)
			(effects
				(font
					(size 1.016 1.016)
					(thickness 0.1524)
				)
			)
		)
		(duplicate_pad_numbers_are_jumpers no)
		(fp_line
			(start 0.508 -0.9398)
			(end -0.508 -0.9398)
			(stroke
				(width 0.1524)
				(type default)
			)
			(layer "F.SilkS")
		)
		(fp_line
			(start -0.508 -0.9398)
			(end -0.508 0.9398)
			(stroke
				(width 0.1524)
				(type default)
			)
			(layer "F.SilkS")
		)
		(fp_rect
			(start -0.508 0.9398)
			(end 0.508 -0.9398)
			(stroke
				(width 0)
				(type default)
			)
			(fill no)
			(layer "F.CrtYd")
		)
		(fp_rect
			(start -0.508 0.9398)
			(end 0.508 -0.9398)
			(stroke
				(width 0)
				(type default)
			)
			(fill no)
			(layer "F.Fab")
		)
		(pad "1" smd custom
			(at 0 -0.4445 180)
			(size 0.1397 0.1397)
			(layers "F.Cu" "F.Mask" "F.Paste")
			(net "P3V3")
			(options
				(clearance outline)
				(anchor circle)
			)
			(primitives
				(gr_poly
					(pts
						(arc
							(start -0.1778 -0.2794)
							(mid -0.249642 -0.249642)
							(end -0.2794 -0.1778)
						)
						(arc
							(start -0.2794 0.1778)
							(mid -0.249642 0.249642)
							(end -0.1778 0.2794)
						)
						(arc
							(start 0.1778 0.2794)
							(mid 0.249642 0.249642)
							(end 0.2794 0.1778)
						)
						(arc
							(start 0.2794 -0.1778)
							(mid 0.249642 -0.249642)
							(end 0.1778 -0.2794)
						)
					)
					(width 0)
					(fill yes)
				)
			)
		)
		(pad "2" smd custom
			(at 0 0.4445 180)
			(size 0.1397 0.1397)
			(layers "F.Cu" "F.Mask" "F.Paste")
			(net "SSD_ACT_DR9_MOS_N")
			(options
				(clearance outline)
				(anchor circle)
			)
			(primitives
				(gr_poly
					(pts
						(arc
							(start -0.1778 -0.2794)
							(mid -0.249642 -0.249642)
							(end -0.2794 -0.1778)
						)
						(arc
							(start -0.2794 0.1778)
							(mid -0.249642 0.249642)
							(end -0.1778 0.2794)
						)
						(arc
							(start 0.1778 0.2794)
							(mid 0.249642 0.249642)
							(end 0.2794 0.1778)
						)
						(arc
							(start 0.2794 -0.1778)
							(mid 0.249642 -0.249642)
							(end 0.1778 -0.2794)
						)
					)
					(width 0)
					(fill yes)
				)
			)
		)
	)
	(footprint ""
		(layer "F.Cu")
		(at 20.828 -165.354 180)
		(property "Reference" "C9531"
			(at 0 0 180)
			(layer "F.SilkS")
			(hide yes)
			(effects
				(font
					(size 1.27 1.27)
				)
			)
		)
		(property "Value" "SCD1U16V2KX-3GP"
			(at 1.1811 -2.7051 180)
			(unlocked yes)
			(layer "F.Fab")
			(hide yes)
			(effects
				(font
					(size 1.016 1.016)
					(thickness 0.1524)
				)
			)
		)
		(property "Device Type" "C402H22"
			(at 1.1811 -4.2291 180)
			(unlocked yes)
			(layer "F.Fab")
			(hide yes)
			(effects
				(font
					(size 1.016 1.016)
					(thickness 0.1524)
				)
			)
		)
		(duplicate_pad_numbers_are_jumpers no)
		(fp_rect
			(start -0.4318 0.9525)
			(end 0.4318 -0.9525)
			(stroke
				(width 0)
				(type default)
			)
			(fill no)
			(layer "F.CrtYd")
		)
		(fp_rect
			(start -0.4318 0.9525)
			(end 0.4318 -0.9525)
			(stroke
				(width 0)
				(type default)
			)
			(fill no)
			(layer "F.Fab")
		)
		(pad "1" smd custom
			(at 0 -0.4445 180)
			(size 0.1524 0.1524)
			(layers "F.Cu" "F.Mask" "F.Paste")
			(net "P3V3")
			(options
				(clearance outline)
				(anchor circle)
			)
			(primitives
				(gr_poly
					(pts
						(arc
							(start 0.3048 -0.2032)
							(mid 0.275042 -0.275042)
							(end 0.2032 -0.3048)
						)
						(arc
							(start -0.2032 -0.3048)
							(mid -0.275042 -0.275042)
							(end -0.3048 -0.2032)
						)
						(arc
							(start -0.3048 0.2032)
							(mid -0.275042 0.275042)
							(end -0.2032 0.3048)
						)
						(arc
							(start 0.2032 0.3048)
							(mid 0.275042 0.275042)
							(end 0.3048 0.2032)
						)
					)
					(width 0)
					(fill yes)
				)
			)
		)
		(pad "2" smd custom
			(at 0 0.4445 180)
			(size 0.1524 0.1524)
			(layers "F.Cu" "F.Mask" "F.Paste")
			(net "GND")
			(options
				(clearance outline)
				(anchor circle)
			)
			(primitives
				(gr_poly
					(pts
						(arc
							(start 0.3048 -0.2032)
							(mid 0.275042 -0.275042)
							(end 0.2032 -0.3048)
						)
						(arc
							(start -0.2032 -0.3048)
							(mid -0.275042 -0.275042)
							(end -0.3048 -0.2032)
						)
						(arc
							(start -0.3048 0.2032)
							(mid -0.275042 0.275042)
							(end -0.2032 0.3048)
						)
						(arc
							(start 0.2032 0.3048)
							(mid 0.275042 0.275042)
							(end 0.3048 0.2032)
						)
					)
					(width 0)
					(fill yes)
				)
			)
		)
	)
	(footprint ""
		(layer "F.Cu")
		(at 32.6136 -417.0934 90)
		(property "Reference" "U19"
			(at 0 0 90)
			(layer "F.SilkS")
			(hide yes)
			(effects
				(font
					(size 1.27 1.27)
				)
			)
		)
		(property "Value" "P2003EVG-GP"
			(at 0 -11.1252 90)
			(unlocked yes)
			(layer "F.Fab")
			(hide yes)
			(effects
				(font
					(size 1.016 1.016)
					(thickness 0.1524)
				)
			)
		)
		(property "Device Type" "SOIC8H79"
			(at 0 -12.6492 90)
			(unlocked yes)
			(layer "F.Fab")
			(hide yes)
			(effects
				(font
					(size 1.016 1.016)
					(thickness 0.1524)
				)
			)
		)
		(duplicate_pad_numbers_are_jumpers no)
		(fp_line
			(start 2.1336 -1.4224)
			(end -2.7432 -1.4224)
			(stroke
				(width 0.1524)
				(type default)
			)
			(layer "F.SilkS")
		)
		(fp_line
			(start -2.7432 -1.4224)
			(end -2.7432 1.4224)
			(stroke
				(width 0.1524)
				(type default)
			)
			(layer "F.SilkS")
		)
		(fp_line
			(start -2.7432 -0.508)
			(end -2.2352 0)
			(stroke
				(width 0.1524)
				(type default)
			)
			(layer "F.SilkS")
		)
		(fp_line
			(start -2.2352 0)
			(end -2.7432 0.508)
			(stroke
				(width 0.1524)
				(type default)
			)
			(layer "F.SilkS")
		)
		(fp_line
			(start 2.1336 1.4224)
			(end 2.1336 -1.4224)
			(stroke
				(width 0.1524)
				(type default)
			)
			(layer "F.SilkS")
		)
		(fp_line
			(start -2.7432 1.4224)
			(end 2.1336 1.4224)
			(stroke
				(width 0.1524)
				(type default)
			)
			(layer "F.SilkS")
		)
		(fp_line
			(start -2.6162 3.429)
			(end -2.6162 1.4732)
			(stroke
				(width 0.4064)
				(type default)
			)
			(layer "F.SilkS")
		)
		(fp_poly
			(pts
				(xy 2.2098 -1.4224) (xy 2.2098 1.4224) (xy -2.2225 1.4224) (xy -2.2225 -1.4224)
			)
			(stroke
				(width 0)
				(type default)
			)
			(fill yes)
			(layer "F.SilkS")
		)
		(fp_rect
			(start -2.4511 2.9972)
			(end 2.4511 -2.9972)
			(stroke
				(width 0)
				(type default)
			)
			(fill no)
			(layer "F.CrtYd")
		)
		(fp_poly
			(pts
				(xy -2.8194 3.6322) (xy -2.8194 -3.6322) (xy 2.8194 -3.6322) (xy 2.8194 -2.2987) (xy 2.4511 -2.2987)
				(xy 2.4511 -2.9972) (xy -2.4511 -2.9972) (xy -2.4511 2.9972) (xy 2.4511 2.9972) (xy 2.4511 -2.286)
				(xy 2.8194 -2.286) (xy 2.8194 3.6322)
			)
			(stroke
				(width 0)
				(type default)
			)
			(fill no)
			(layer "F.CrtYd")
		)
		(fp_rect
			(start -2.8194 3.6322)
			(end 2.8194 -3.6322)
			(stroke
				(width 0)
				(type default)
			)
			(fill no)
			(layer "F.Fab")
		)
		(pad "1" smd rect
			(at -1.905 2.54 90)
			(size 0.635 1.651)
			(layers "F.Cu" "F.Mask" "F.Paste")
			(net "P12V")
		)
		(pad "2" smd rect
			(at -0.635 2.54 90)
			(size 0.635 1.651)
			(layers "F.Cu" "F.Mask" "F.Paste")
			(net "P12V")
		)
		(pad "3" smd rect
			(at 0.635 2.54 90)
			(size 0.635 1.651)
			(layers "F.Cu" "F.Mask" "F.Paste")
			(net "P12V")
		)
		(pad "4" smd rect
			(at 1.905 2.54 90)
			(size 0.635 1.651)
			(layers "F.Cu" "F.Mask" "F.Paste")
			(net "SW_SSD10_N")
		)
		(pad "5" smd rect
			(at 1.905 -2.54 90)
			(size 0.635 1.651)
			(layers "F.Cu" "F.Mask" "F.Paste")
			(net "P12V_SSD10")
		)
		(pad "6" smd rect
			(at 0.635 -2.54 90)
			(size 0.635 1.651)
			(layers "F.Cu" "F.Mask" "F.Paste")
			(net "P12V_SSD10")
		)
		(pad "7" smd rect
			(at -0.635 -2.54 90)
			(size 0.635 1.651)
			(layers "F.Cu" "F.Mask" "F.Paste")
			(net "P12V_SSD10")
		)
		(pad "8" smd rect
			(at -1.905 -2.54 90)
			(size 0.635 1.651)
			(layers "F.Cu" "F.Mask" "F.Paste")
			(net "P12V_SSD10")
		)
	)
	(footprint ""
		(layer "F.Cu")
		(at 221.0054 -404.9776 -90)
		(property "Reference" "R9784"
			(at 0 0 270)
			(layer "F.SilkS")
			(hide yes)
			(effects
				(font
					(size 1.27 1.27)
				)
			)
		)
		(property "Value" "2K2R5F-GP"
			(at 0 -8.9535 270)
			(unlocked yes)
			(layer "F.Fab")
			(hide yes)
			(effects
				(font
					(size 1.27 1.016)
					(thickness 0.1524)
				)
			)
		)
		(property "Device Type" "R805H24"
			(at 0 -10.6299 270)
			(unlocked yes)
			(layer "F.Fab")
			(hide yes)
			(effects
				(font
					(size 1.27 1.016)
					(thickness 0.1524)
				)
			)
		)
		(duplicate_pad_numbers_are_jumpers no)
		(fp_line
			(start -0.889 1.7018)
			(end 0.889 1.7018)
			(stroke
				(width 0.1524)
				(type default)
			)
			(layer "F.SilkS")
		)
		(fp_line
			(start 0.889 1.7018)
			(end 0.889 -0.508)
			(stroke
				(width 0.1524)
				(type default)
			)
			(layer "F.SilkS")
		)
		(fp_line
			(start -0.889 0.0762)
			(end -0.889 1.7018)
			(stroke
				(width 0.1524)
				(type default)
			)
			(layer "F.SilkS")
		)
		(fp_line
			(start -0.889 -1.7018)
			(end -0.889 0.2794)
			(stroke
				(width 0.1524)
				(type default)
			)
			(layer "F.SilkS")
		)
		(fp_line
			(start 0.889 -1.7018)
			(end 0.889 -0.381)
			(stroke
				(width 0.1524)
				(type default)
			)
			(layer "F.SilkS")
		)
		(fp_line
			(start 0.889 -1.7018)
			(end -0.889 -1.7018)
			(stroke
				(width 0.1524)
				(type default)
			)
			(layer "F.SilkS")
		)
		(fp_poly
			(pts
				(xy 0.9652 -1.778) (xy 0.9652 1.778) (xy -0.9652 1.778) (xy -0.9652 -1.778)
			)
			(stroke
				(width 0)
				(type default)
			)
			(fill no)
			(layer "F.CrtYd")
		)
		(fp_rect
			(start -0.9652 1.778)
			(end 0.9652 -1.778)
			(stroke
				(width 0)
				(type default)
			)
			(fill no)
			(layer "F.Fab")
		)
		(pad "1" smd rect
			(at 0 -0.9652 270)
			(size 1.397 1.143)
			(layers "F.Cu" "F.Mask" "F.Paste")
			(net "P12V_SSD1")
		)
		(pad "2" smd rect
			(at 0 0.9652 270)
			(size 1.397 1.143)
			(layers "F.Cu" "F.Mask" "F.Paste")
			(net "P12V_MOST1_GATE_D")
		)
	)
	(footprint ""
		(layer "F.Cu")
		(at 102.616 -433.324 90)
		(property "Reference" "R9057"
			(at 0 0 90)
			(layer "F.SilkS")
			(hide yes)
			(effects
				(font
					(size 1.27 1.27)
				)
			)
		)
		(property "Value" "27R2F-GP"
			(at 0.064008 -3.993896 90)
			(unlocked yes)
			(layer "F.Fab")
			(hide yes)
			(effects
				(font
					(size 1.016 1.016)
					(thickness 0.1524)
				)
			)
		)
		(property "Device Type" "R402H16"
			(at 0.064008 -5.517896 90)
			(unlocked yes)
			(layer "F.Fab")
			(hide yes)
			(effects
				(font
					(size 1.016 1.016)
					(thickness 0.1524)
				)
			)
		)
		(duplicate_pad_numbers_are_jumpers no)
		(fp_line
			(start 0.508 -0.9398)
			(end -0.508 -0.9398)
			(stroke
				(width 0.1524)
				(type default)
			)
			(layer "F.SilkS")
		)
		(fp_line
			(start -0.508 -0.9398)
			(end -0.508 0.9398)
			(stroke
				(width 0.1524)
				(type default)
			)
			(layer "F.SilkS")
		)
		(fp_rect
			(start -0.508 0.9398)
			(end 0.508 -0.9398)
			(stroke
				(width 0)
				(type default)
			)
			(fill no)
			(layer "F.CrtYd")
		)
		(fp_rect
			(start -0.508 0.9398)
			(end 0.508 -0.9398)
			(stroke
				(width 0)
				(type default)
			)
			(fill no)
			(layer "F.Fab")
		)
		(pad "1" smd custom
			(at 0 -0.4445 90)
			(size 0.1397 0.1397)
			(layers "F.Cu" "F.Mask" "F.Paste")
			(net "PE_CLK_100M_DR0_2_R_P")
			(options
				(clearance outline)
				(anchor circle)
			)
			(primitives
				(gr_poly
					(pts
						(arc
							(start -0.1778 -0.2794)
							(mid -0.249642 -0.249642)
							(end -0.2794 -0.1778)
						)
						(arc
							(start -0.2794 0.1778)
							(mid -0.249642 0.249642)
							(end -0.1778 0.2794)
						)
						(arc
							(start 0.1778 0.2794)
							(mid 0.249642 0.249642)
							(end 0.2794 0.1778)
						)
						(arc
							(start 0.2794 -0.1778)
							(mid 0.249642 -0.249642)
							(end 0.1778 -0.2794)
						)
					)
					(width 0)
					(fill yes)
				)
			)
		)
		(pad "2" smd custom
			(at 0 0.4445 90)
			(size 0.1397 0.1397)
			(layers "F.Cu" "F.Mask" "F.Paste")
			(net "PE_CLK100M_DR0_2_P")
			(options
				(clearance outline)
				(anchor circle)
			)
			(primitives
				(gr_poly
					(pts
						(arc
							(start -0.1778 -0.2794)
							(mid -0.249642 -0.249642)
							(end -0.2794 -0.1778)
						)
						(arc
							(start -0.2794 0.1778)
							(mid -0.249642 0.249642)
							(end -0.1778 0.2794)
						)
						(arc
							(start 0.1778 0.2794)
							(mid 0.249642 0.249642)
							(end 0.2794 0.1778)
						)
						(arc
							(start 0.2794 -0.1778)
							(mid 0.249642 -0.249642)
							(end 0.1778 -0.2794)
						)
					)
					(width 0)
					(fill yes)
				)
			)
		)
	)
	(footprint ""
		(layer "F.Cu")
		(at 49.429924 -449.88226 180)
		(property "Reference" "C9523"
			(at 0 0 180)
			(layer "F.SilkS")
			(hide yes)
			(effects
				(font
					(size 1.27 1.27)
				)
			)
		)
		(property "Value" "SCD1U16V2KX-3GP"
			(at 1.1811 -2.7051 180)
			(unlocked yes)
			(layer "F.Fab")
			(hide yes)
			(effects
				(font
					(size 1.016 1.016)
					(thickness 0.1524)
				)
			)
		)
		(property "Device Type" "C402H22"
			(at 1.1811 -4.2291 180)
			(unlocked yes)
			(layer "F.Fab")
			(hide yes)
			(effects
				(font
					(size 1.016 1.016)
					(thickness 0.1524)
				)
			)
		)
		(duplicate_pad_numbers_are_jumpers no)
		(fp_rect
			(start -0.4318 0.9525)
			(end 0.4318 -0.9525)
			(stroke
				(width 0)
				(type default)
			)
			(fill no)
			(layer "F.CrtYd")
		)
		(fp_rect
			(start -0.4318 0.9525)
			(end 0.4318 -0.9525)
			(stroke
				(width 0)
				(type default)
			)
			(fill no)
			(layer "F.Fab")
		)
		(pad "1" smd custom
			(at 0 -0.4445 180)
			(size 0.1524 0.1524)
			(layers "F.Cu" "F.Mask" "F.Paste")
			(net "P3V3")
			(options
				(clearance outline)
				(anchor circle)
			)
			(primitives
				(gr_poly
					(pts
						(arc
							(start 0.3048 -0.2032)
							(mid 0.275042 -0.275042)
							(end 0.2032 -0.3048)
						)
						(arc
							(start -0.2032 -0.3048)
							(mid -0.275042 -0.275042)
							(end -0.3048 -0.2032)
						)
						(arc
							(start -0.3048 0.2032)
							(mid -0.275042 0.275042)
							(end -0.2032 0.3048)
						)
						(arc
							(start 0.2032 0.3048)
							(mid 0.275042 0.275042)
							(end 0.3048 0.2032)
						)
					)
					(width 0)
					(fill yes)
				)
			)
		)
		(pad "2" smd custom
			(at 0 0.4445 180)
			(size 0.1524 0.1524)
			(layers "F.Cu" "F.Mask" "F.Paste")
			(net "GND")
			(options
				(clearance outline)
				(anchor circle)
			)
			(primitives
				(gr_poly
					(pts
						(arc
							(start 0.3048 -0.2032)
							(mid 0.275042 -0.275042)
							(end 0.2032 -0.3048)
						)
						(arc
							(start -0.2032 -0.3048)
							(mid -0.275042 -0.275042)
							(end -0.3048 -0.2032)
						)
						(arc
							(start -0.3048 0.2032)
							(mid -0.275042 0.275042)
							(end -0.2032 0.3048)
						)
						(arc
							(start 0.2032 0.3048)
							(mid 0.275042 0.275042)
							(end 0.3048 0.2032)
						)
					)
					(width 0)
					(fill yes)
				)
			)
		)
	)
)
